(kicad_pcb
	(version 20260206)
	(generator "pcbnew")
	(generator_version "10.0")
	(general
		(thickness 1.6)
		(legacy_teardrops no)
	)
	(paper "A4")
	(title_block
		(title "dpb — 14545-sa.0730WZS0815.brd")
		(comment 1 "Honey Badger (Wiwynn) / footprints 978-983 of 1066")
	)
	(layers
		(0 "F.Cu" signal "TOP")
		(4 "In1.Cu" signal "L2GND")
		(6 "In2.Cu" signal "L3")
		(8 "In3.Cu" signal "L4VCC")
		(10 "In4.Cu" signal "L5VCC")
		(12 "In5.Cu" signal "L6")
		(14 "In6.Cu" signal "L7GND")
		(2 "B.Cu" signal "BOTTOM")
		(9 "F.Adhes" user "F.Adhesive")
		(11 "B.Adhes" user "B.Adhesive")
		(13 "F.Paste" user "Package Geometry/Pastemask Top")
		(15 "B.Paste" user "Package Geometry/Pastemask Bottom")
		(5 "F.SilkS" user "Ref Des/Silkscreen Top")
		(7 "B.SilkS" user "Ref Des/Silkscreen Bottom")
		(1 "F.Mask" user "Board Geometry/Soldermask Top")
		(3 "B.Mask" user "Board Geometry/Soldermask Bottom")
		(17 "Dwgs.User" user "User.Drawings")
		(19 "Cmts.User" user "User.Comments")
		(21 "Eco1.User" user "User.Eco1")
		(23 "Eco2.User" user "User.Eco2")
		(25 "Edge.Cuts" user "Board Geometry/Outline")
		(27 "Margin" user)
		(31 "F.CrtYd" user "Package Geometry/Place Bound Top")
		(29 "B.CrtYd" user "Package Geometry/Place Bound Bottom")
		(35 "F.Fab" user "Ref Des/Assembly Top")
		(33 "B.Fab" user "Ref Des/Assembly Bottom")
	)
	(footprint ""
		(layer "F.Cu")
		(at 29.590746 -311.305702)
		(property "Reference" "R266"
			(at 0 0 0)
			(layer "F.SilkS")
			(hide yes)
			(effects
				(font
					(size 1.27 1.27)
				)
			)
		)
		(property "Value" "0R2J-2-GP"
			(at 0.064008 -3.993896 0)
			(unlocked yes)
			(layer "F.Fab")
			(hide yes)
			(effects
				(font
					(size 1.016 1.016)
					(thickness 0.1524)
				)
			)
		)
		(property "Device Type" "R402H16"
			(at 0.064008 -5.517896 0)
			(unlocked yes)
			(layer "F.Fab")
			(hide yes)
			(effects
				(font
					(size 1.016 1.016)
					(thickness 0.1524)
				)
			)
		)
		(duplicate_pad_numbers_are_jumpers no)
		(fp_line
			(start -0.508 -0.9398)
			(end -0.508 0.9398)
			(stroke
				(width 0.1524)
				(type default)
			)
			(layer "F.SilkS")
		)
		(fp_line
			(start 0.508 -0.9398)
			(end -0.508 -0.9398)
			(stroke
				(width 0.1524)
				(type default)
			)
			(layer "F.SilkS")
		)
		(fp_rect
			(start -0.508 0.9398)
			(end 0.508 -0.9398)
			(stroke
				(width 0)
				(type default)
			)
			(fill no)
			(layer "F.CrtYd")
		)
		(fp_rect
			(start -0.508 0.9398)
			(end 0.508 -0.9398)
			(stroke
				(width 0)
				(type default)
			)
			(fill no)
			(layer "F.Fab")
		)
		(pad "1" smd custom
			(at 0 -0.4445)
			(size 0.1397 0.1397)
			(layers "F.Cu" "F.Mask" "F.Paste")
			(net "SW_PWR_HDD11")
			(options
				(clearance outline)
				(anchor circle)
			)
			(primitives
				(gr_poly
					(pts
						(arc
							(start -0.1778 -0.2794)
							(mid -0.249642 -0.249642)
							(end -0.2794 -0.1778)
						)
						(arc
							(start -0.2794 0.1778)
							(mid -0.249642 0.249642)
							(end -0.1778 0.2794)
						)
						(arc
							(start 0.1778 0.2794)
							(mid 0.249642 0.249642)
							(end 0.2794 0.1778)
						)
						(arc
							(start 0.2794 -0.1778)
							(mid 0.249642 -0.249642)
							(end 0.1778 -0.2794)
						)
					)
					(width 0)
					(fill yes)
				)
			)
		)
		(pad "2" smd custom
			(at 0 0.4445)
			(size 0.1397 0.1397)
			(layers "F.Cu" "F.Mask" "F.Paste")
			(net "SW_PWR_R_HDD11")
			(options
				(clearance outline)
				(anchor circle)
			)
			(primitives
				(gr_poly
					(pts
						(arc
							(start -0.1778 -0.2794)
							(mid -0.249642 -0.249642)
							(end -0.2794 -0.1778)
						)
						(arc
							(start -0.2794 0.1778)
							(mid -0.249642 0.249642)
							(end -0.1778 0.2794)
						)
						(arc
							(start 0.1778 0.2794)
							(mid 0.249642 0.249642)
							(end 0.2794 0.1778)
						)
						(arc
							(start 0.2794 -0.1778)
							(mid 0.249642 -0.249642)
							(end 0.1778 -0.2794)
						)
					)
					(width 0)
					(fill yes)
				)
			)
		)
	)
	(footprint ""
		(layer "F.Cu")
		(at 58.165492 -87.912956 180)
		(property "Reference" "C257"
			(at 0 0 180)
			(layer "F.SilkS")
			(hide yes)
			(effects
				(font
					(size 1.27 1.27)
				)
			)
		)
		(property "Value" "SC10U25V6KX-1GP"
			(at -0.0762 -5.1308 180)
			(unlocked yes)
			(layer "F.Fab")
			(hide yes)
			(effects
				(font
					(size 1.016 1.016)
					(thickness 0.1524)
				)
			)
		)
		(property "Device Type" "C1206H71"
			(at -0.127 -6.6548 180)
			(unlocked yes)
			(layer "F.Fab")
			(hide yes)
			(effects
				(font
					(size 1.016 1.016)
					(thickness 0.1524)
				)
			)
		)
		(duplicate_pad_numbers_are_jumpers no)
		(fp_line
			(start 1.016 2.2352)
			(end -1.016 2.2352)
			(stroke
				(width 0.1524)
				(type default)
			)
			(layer "F.SilkS")
		)
		(fp_line
			(start 1.016 0.8382)
			(end 1.016 2.2352)
			(stroke
				(width 0.1524)
				(type default)
			)
			(layer "F.SilkS")
		)
		(fp_line
			(start 1.016 -2.2352)
			(end 1.016 -0.8382)
			(stroke
				(width 0.1524)
				(type default)
			)
			(layer "F.SilkS")
		)
		(fp_line
			(start -1.016 2.2352)
			(end -1.016 0.8382)
			(stroke
				(width 0.1524)
				(type default)
			)
			(layer "F.SilkS")
		)
		(fp_line
			(start -1.016 -0.8382)
			(end -1.016 -2.2352)
			(stroke
				(width 0.1524)
				(type default)
			)
			(layer "F.SilkS")
		)
		(fp_line
			(start -1.016 -2.2352)
			(end 1.016 -2.2352)
			(stroke
				(width 0.1524)
				(type default)
			)
			(layer "F.SilkS")
		)
		(fp_rect
			(start -1.0922 2.3114)
			(end 1.0922 -2.3114)
			(stroke
				(width 0)
				(type default)
			)
			(fill no)
			(layer "F.CrtYd")
		)
		(fp_poly
			(pts
				(xy 1.0922 -2.3114) (xy 1.0922 2.3114) (xy -1.0922 2.3114) (xy -1.0922 -2.3114)
			)
			(stroke
				(width 0)
				(type default)
			)
			(fill no)
			(layer "F.Fab")
		)
		(pad "1" smd rect
			(at 0 -1.397 180)
			(size 1.651 1.27)
			(layers "F.Cu" "F.Mask" "F.Paste")
			(net "P12V_HDD9")
		)
		(pad "2" smd rect
			(at 0 1.397 180)
			(size 1.651 1.27)
			(layers "F.Cu" "F.Mask" "F.Paste")
			(net "GND")
		)
	)
	(footprint ""
		(layer "F.Cu")
		(at 194.322446 -458.504036 -90)
		(property "Reference" "U50"
			(at 0 0 270)
			(layer "F.SilkS")
			(hide yes)
			(effects
				(font
					(size 1.27 1.27)
				)
			)
		)
		(property "Value" "24LC64T-I-GP"
			(at 0 -12.1412 270)
			(unlocked yes)
			(layer "F.Fab")
			(hide yes)
			(effects
				(font
					(size 1.016 1.016)
					(thickness 0.1524)
				)
			)
		)
		(property "Device Type" "SSOIC8-1H44"
			(at 0 -13.6652 270)
			(unlocked yes)
			(layer "F.Fab")
			(hide yes)
			(effects
				(font
					(size 1.016 1.016)
					(thickness 0.1524)
				)
			)
		)
		(duplicate_pad_numbers_are_jumpers no)
		(fp_line
			(start -1.778 1.778)
			(end -1.778 3.81)
			(stroke
				(width 0.508)
				(type default)
			)
			(layer "F.SilkS")
		)
		(fp_line
			(start 1.397 1.778)
			(end -1.778 1.778)
			(stroke
				(width 0.2032)
				(type default)
			)
			(layer "F.SilkS")
		)
		(fp_line
			(start -1.143 0)
			(end -1.778 0.635)
			(stroke
				(width 0.2032)
				(type default)
			)
			(layer "F.SilkS")
		)
		(fp_line
			(start -1.143 0)
			(end -1.778 -0.635)
			(stroke
				(width 0.2032)
				(type default)
			)
			(layer "F.SilkS")
		)
		(fp_line
			(start -1.778 -1.778)
			(end -1.778 2.667)
			(stroke
				(width 0.2032)
				(type default)
			)
			(layer "F.SilkS")
		)
		(fp_line
			(start -1.778 -1.778)
			(end 1.397 -1.778)
			(stroke
				(width 0.2032)
				(type default)
			)
			(layer "F.SilkS")
		)
		(fp_line
			(start 1.397 -1.778)
			(end 1.397 1.778)
			(stroke
				(width 0.2032)
				(type default)
			)
			(layer "F.SilkS")
		)
		(fp_poly
			(pts
				(xy -2.032 3.81) (xy 2.032 3.81) (xy 2.032 -3.81) (xy -2.032 -3.81)
			)
			(stroke
				(width 0)
				(type default)
			)
			(fill no)
			(layer "F.CrtYd")
		)
		(fp_poly
			(pts
				(xy -2.032 -3.81) (xy 2.032 -3.81) (xy 2.032 3.81) (xy -2.032 3.81)
			)
			(stroke
				(width 0)
				(type default)
			)
			(fill no)
			(layer "F.Fab")
		)
		(pad "1" smd rect
			(at -0.97536 2.8194 270)
			(size 0.3556 1.524)
			(layers "F.Cu" "F.Mask" "F.Paste")
			(net "EEPROM_A0")
		)
		(pad "2" smd rect
			(at -0.32512 2.8194 270)
			(size 0.3556 1.524)
			(layers "F.Cu" "F.Mask" "F.Paste")
			(net "EEPROM_A1")
		)
		(pad "3" smd rect
			(at 0.32512 2.8194 270)
			(size 0.3556 1.524)
			(layers "F.Cu" "F.Mask" "F.Paste")
			(net "EEPROM_A2")
		)
		(pad "4" smd rect
			(at 0.97536 2.8194 270)
			(size 0.3556 1.524)
			(layers "F.Cu" "F.Mask" "F.Paste")
			(net "GND")
		)
		(pad "5" smd rect
			(at 0.97536 -2.8194 270)
			(size 0.3556 1.524)
			(layers "F.Cu" "F.Mask" "F.Paste")
			(net "EEPROM_SDA")
		)
		(pad "6" smd rect
			(at 0.32512 -2.8194 270)
			(size 0.3556 1.524)
			(layers "F.Cu" "F.Mask" "F.Paste")
			(net "EEPROM_SCL")
		)
		(pad "7" smd rect
			(at -0.32512 -2.8194 270)
			(size 0.3556 1.524)
			(layers "F.Cu" "F.Mask" "F.Paste")
			(net "EEPROM_WP")
		)
		(pad "8" smd rect
			(at -0.97536 -2.8194 270)
			(size 0.3556 1.524)
			(layers "F.Cu" "F.Mask" "F.Paste")
			(net "P3V3")
		)
	)
	(footprint ""
		(layer "F.Cu")
		(at 237.692946 -42.5958 90)
		(property "Reference" "Q38"
			(at 0 0 90)
			(layer "F.SilkS")
			(hide yes)
			(effects
				(font
					(size 1.27 1.27)
				)
			)
		)
		(property "Value" "PMBS3904-1-GP"
			(at 0 -9.0932 90)
			(unlocked yes)
			(layer "F.Fab")
			(hide yes)
			(effects
				(font
					(size 1.016 1.016)
					(thickness 0.1524)
				)
			)
		)
		(property "Device Type" "SOT-23-10H44"
			(at 0 -10.6172 90)
			(unlocked yes)
			(layer "F.Fab")
			(hide yes)
			(effects
				(font
					(size 1.016 1.016)
					(thickness 0.1524)
				)
			)
		)
		(duplicate_pad_numbers_are_jumpers no)
		(fp_line
			(start 1.651 -1.778)
			(end -1.651 -1.778)
			(stroke
				(width 0.1524)
				(type default)
			)
			(layer "F.SilkS")
		)
		(fp_line
			(start -1.651 -1.778)
			(end -1.651 1.778)
			(stroke
				(width 0.1524)
				(type default)
			)
			(layer "F.SilkS")
		)
		(fp_line
			(start 1.651 1.778)
			(end 1.651 -1.778)
			(stroke
				(width 0.1524)
				(type default)
			)
			(layer "F.SilkS")
		)
		(fp_line
			(start -1.651 1.778)
			(end 1.651 1.778)
			(stroke
				(width 0.1524)
				(type default)
			)
			(layer "F.SilkS")
		)
		(fp_line
			(start -0.9906 1.86309)
			(end -0.701294 2.15265)
			(stroke
				(width 0.0127)
				(type default)
			)
			(layer "F.SilkS")
		)
		(fp_line
			(start -0.994156 1.8669)
			(end -0.987044 1.8669)
			(stroke
				(width 0.0127)
				(type default)
			)
			(layer "F.SilkS")
		)
		(fp_line
			(start -1.003808 1.876552)
			(end -0.977646 1.876552)
			(stroke
				(width 0.0127)
				(type default)
			)
			(layer "F.SilkS")
		)
		(fp_line
			(start -0.635 1.8796)
			(end -1.7526 1.8796)
			(stroke
				(width 0.3302)
				(type default)
			)
			(layer "F.SilkS")
		)
		(fp_line
			(start -1.7526 1.8796)
			(end -1.7526 0.9906)
			(stroke
				(width 0.3302)
				(type default)
			)
			(layer "F.SilkS")
		)
		(fp_line
			(start -1.013206 1.88595)
			(end -0.967994 1.88595)
			(stroke
				(width 0.0127)
				(type default)
			)
			(layer "F.SilkS")
		)
		(fp_line
			(start -1.022858 1.895602)
			(end -0.958596 1.895602)
			(stroke
				(width 0.0127)
				(type default)
			)
			(layer "F.SilkS")
		)
		(fp_line
			(start -1.032256 1.905)
			(end -0.948944 1.905)
			(stroke
				(width 0.0127)
				(type default)
			)
			(layer "F.SilkS")
		)
		(fp_line
			(start -1.041908 1.914652)
			(end -0.939546 1.914652)
			(stroke
				(width 0.0127)
				(type default)
			)
			(layer "F.SilkS")
		)
		(fp_line
			(start -1.051306 1.92405)
			(end -0.929894 1.92405)
			(stroke
				(width 0.0127)
				(type default)
			)
			(layer "F.SilkS")
		)
		(fp_line
			(start -1.060958 1.933702)
			(end -0.920496 1.933702)
			(stroke
				(width 0.0127)
				(type default)
			)
			(layer "F.SilkS")
		)
		(fp_line
			(start -1.070356 1.9431)
			(end -0.910844 1.9431)
			(stroke
				(width 0.0127)
				(type default)
			)
			(layer "F.SilkS")
		)
		(fp_line
			(start -1.080008 1.952752)
			(end -0.901446 1.952752)
			(stroke
				(width 0.0127)
				(type default)
			)
			(layer "F.SilkS")
		)
		(fp_line
			(start -1.089406 1.96215)
			(end -0.891794 1.96215)
			(stroke
				(width 0.0127)
				(type default)
			)
			(layer "F.SilkS")
		)
		(fp_line
			(start -1.099058 1.971802)
			(end -0.882396 1.971802)
			(stroke
				(width 0.0127)
				(type default)
			)
			(layer "F.SilkS")
		)
		(fp_line
			(start -1.108456 1.9812)
			(end -0.872744 1.9812)
			(stroke
				(width 0.0127)
				(type default)
			)
			(layer "F.SilkS")
		)
		(fp_line
			(start -1.118108 1.990852)
			(end -0.863346 1.990852)
			(stroke
				(width 0.0127)
				(type default)
			)
			(layer "F.SilkS")
		)
		(fp_line
			(start -1.127506 2.00025)
			(end -0.853694 2.00025)
			(stroke
				(width 0.0127)
				(type default)
			)
			(layer "F.SilkS")
		)
		(fp_line
			(start -1.137158 2.009902)
			(end -0.844296 2.009902)
			(stroke
				(width 0.0127)
				(type default)
			)
			(layer "F.SilkS")
		)
		(fp_line
			(start -1.146556 2.0193)
			(end -0.834644 2.0193)
			(stroke
				(width 0.0127)
				(type default)
			)
			(layer "F.SilkS")
		)
		(fp_line
			(start -1.156208 2.028952)
			(end -0.825246 2.028952)
			(stroke
				(width 0.0127)
				(type default)
			)
			(layer "F.SilkS")
		)
		(fp_line
			(start -1.165606 2.03835)
			(end -0.815594 2.03835)
			(stroke
				(width 0.0127)
				(type default)
			)
			(layer "F.SilkS")
		)
		(fp_line
			(start -1.175258 2.048002)
			(end -0.806196 2.048002)
			(stroke
				(width 0.0127)
				(type default)
			)
			(layer "F.SilkS")
		)
		(fp_line
			(start -1.184656 2.0574)
			(end -0.796544 2.0574)
			(stroke
				(width 0.0127)
				(type default)
			)
			(layer "F.SilkS")
		)
		(fp_line
			(start -1.194308 2.067052)
			(end -0.787146 2.067052)
			(stroke
				(width 0.0127)
				(type default)
			)
			(layer "F.SilkS")
		)
		(fp_line
			(start -1.203706 2.07645)
			(end -0.777494 2.07645)
			(stroke
				(width 0.0127)
				(type default)
			)
			(layer "F.SilkS")
		)
		(fp_line
			(start -1.213358 2.086102)
			(end -0.768096 2.086102)
			(stroke
				(width 0.0127)
				(type default)
			)
			(layer "F.SilkS")
		)
		(fp_line
			(start -1.222756 2.0955)
			(end -0.758444 2.0955)
			(stroke
				(width 0.0127)
				(type default)
			)
			(layer "F.SilkS")
		)
		(fp_line
			(start -1.232408 2.105152)
			(end -0.749046 2.105152)
			(stroke
				(width 0.0127)
				(type default)
			)
			(layer "F.SilkS")
		)
		(fp_line
			(start -1.241806 2.11455)
			(end -0.739394 2.11455)
			(stroke
				(width 0.0127)
				(type default)
			)
			(layer "F.SilkS")
		)
		(fp_line
			(start -1.251458 2.124202)
			(end -0.729996 2.124202)
			(stroke
				(width 0.0127)
				(type default)
			)
			(layer "F.SilkS")
		)
		(fp_line
			(start -1.260856 2.1336)
			(end -0.720344 2.1336)
			(stroke
				(width 0.0127)
				(type default)
			)
			(layer "F.SilkS")
		)
		(fp_line
			(start -0.719074 2.145538)
			(end -1.265936 2.14122)
			(stroke
				(width 0.0127)
				(type default)
			)
			(layer "F.SilkS")
		)
		(fp_line
			(start -1.279398 2.152142)
			(end -0.9906 1.86309)
			(stroke
				(width 0.0127)
				(type default)
			)
			(layer "F.SilkS")
		)
		(fp_line
			(start -0.71628 2.15265)
			(end -1.26492 2.15265)
			(stroke
				(width 0.0127)
				(type default)
			)
			(layer "F.SilkS")
		)
		(fp_line
			(start -1.279144 2.15265)
			(end -0.701294 2.15265)
			(stroke
				(width 0.0127)
				(type default)
			)
			(layer "F.SilkS")
		)
		(fp_poly
			(pts
				(xy -1.285748 2.159) (xy -1.285748 1.8796) (xy -1.778 1.8796) (xy -1.778 -1.8796) (xy 1.778 -1.8796)
				(xy 1.778 1.8796) (xy -0.694944 1.8796) (xy -0.694944 2.159)
			)
			(stroke
				(width 0)
				(type default)
			)
			(fill no)
			(layer "F.CrtYd")
		)
		(fp_poly
			(pts
				(xy -1.285748 2.159) (xy -1.285748 1.8796) (xy -1.778 1.8796) (xy -1.778 -1.8796) (xy 1.778 -1.8796)
				(xy 1.778 1.8796) (xy -0.694944 1.8796) (xy -0.694944 2.159)
			)
			(stroke
				(width 0)
				(type default)
			)
			(fill no)
			(layer "F.Fab")
		)
		(pad "1" smd rect
			(at -0.98425 0.9525 90)
			(size 0.762 1.143)
			(layers "F.Cu" "F.Mask" "F.Paste")
			(net "FLT_HDD4_B")
		)
		(pad "2" smd rect
			(at 0.98425 0.9525 90)
			(size 0.762 1.143)
			(layers "F.Cu" "F.Mask" "F.Paste")
			(net "GND")
		)
		(pad "3" smd rect
			(at 0 -0.9525 90)
			(size 0.762 1.143)
			(layers "F.Cu" "F.Mask" "F.Paste")
			(net "DRIVE_ACT_4")
		)
	)
	(footprint ""
		(layer "F.Cu")
		(at 27.355546 -383.7813)
		(property "Reference" "TP1"
			(at 0 0 0)
			(layer "F.SilkS")
			(hide yes)
			(effects
				(font
					(size 1.27 1.27)
				)
			)
		)
		(property "Value" "TPAD32-GP"
			(at 0 -3.166364 0)
			(unlocked yes)
			(layer "F.Fab")
			(hide yes)
			(effects
				(font
					(size 1.016 1.016)
					(thickness 0.1524)
				)
			)
		)
		(property "Device Type" "TPAD32"
			(at 0 -4.690618 0)
			(unlocked yes)
			(layer "F.Fab")
			(hide yes)
			(effects
				(font
					(size 1.016 1.016)
					(thickness 0.1524)
				)
			)
		)
		(duplicate_pad_numbers_are_jumpers no)
		(fp_poly
			(pts
				(arc
					(start 0.4064 0)
					(mid -0.4064 0)
					(end 0.4064 0)
				)
			)
			(stroke
				(width 0)
				(type default)
			)
			(fill no)
			(layer "F.CrtYd")
		)
		(fp_poly
			(pts
				(arc
					(start 0.7112 0)
					(mid -0.7112 0)
					(end 0.7112 0)
				)
			)
			(stroke
				(width 0)
				(type default)
			)
			(fill no)
			(layer "F.Fab")
		)
		(pad "1" smd circle
			(at 0 0)
			(size 0.8128 0.8128)
			(layers "F.Cu" "F.Mask" "F.Paste")
			(net "I2C_B_TMP1_ALERT")
		)
	)
	(footprint ""
		(layer "F.Cu")
		(at 252.499876 -271.499838)
		(property "Reference" "H14"
			(at 0 0 0)
			(layer "F.SilkS")
			(hide yes)
			(effects
				(font
					(size 1.27 1.27)
				)
			)
		)
		(property "Value" "HOLE315R140"
			(at 0 -7.5692 0)
			(unlocked yes)
			(layer "F.Fab")
			(hide yes)
			(effects
				(font
					(size 1.016 1.016)
					(thickness 0.1524)
				)
			)
		)
		(property "Device Type" "HOLE315R140"
			(at 0 -9.0932 0)
			(unlocked yes)
			(layer "F.Fab")
			(hide yes)
			(effects
				(font
					(size 1.016 1.016)
					(thickness 0.1524)
				)
			)
		)
		(duplicate_pad_numbers_are_jumpers no)
		(fp_poly
			(pts
				(arc
					(start 4.3053 0)
					(mid -4.3053 0)
					(end 4.3053 0)
				)
			)
			(stroke
				(width 0)
				(type default)
			)
			(fill no)
			(layer "F.CrtYd")
		)
		(fp_poly
			(pts
				(arc
					(start 4.3053 0)
					(mid -4.3053 0)
					(end 4.3053 0)
				)
			)
			(stroke
				(width 0)
				(type default)
			)
			(fill no)
			(layer "F.Fab")
		)
		(pad "1" thru_hole circle
			(at 0.00127 0.00127)
			(size 8.001 8.001)
			(drill 3.556)
			(layers "*.Cu" "*.Mask")
			(remove_unused_layers no)
			(net "GND")
			(clearance -1.7145)
			(thermal_gap 0.3048)
			(padstack
				(mode front_inner_back)
				(layer "Inner"
					(shape circle)
					(size 3.9624 3.9624)
					(clearance 0.3048)
				)
				(layer "B.Cu"
					(shape circle)
					(size 8.001 8.001)
					(clearance -1.7145)
				)
			)
		)
	)
)
